# T6G (Grand Teton) — schematic netlist excerpt (pin names and nets, part order shuffled) for the footprints in the layout excerpt that follows; sources: Cadence DE-HDL packaged netlist, KiCad conversion of 04192023_DAF0TMB3IC0_F0TG_MB_C_brd_V02_OCP.brd

PR6820  Q_RES  0 5% CHIP  pkg 0402LF  page 364 : A = P0V9_RETIMER_CPU1_SVID_SDA ; B = GND
C351  Q_CAP  22UF 4V 20% X6S  pkg C0402  page 334 : A = P0V9_CPU1_RT1_2A ; B = GND

(kicad_pcb
	(version 20260206)
	(generator "pcbnew")
	(generator_version "10.0")
	(general
		(thickness 1.6)
		(legacy_teardrops no)
	)
	(paper "A4")
	(title_block
		(title "04192023_DAF0TMB3IC0_F0TG_MB_C_brd_V02_OCP.brd")
		(comment 1 "Grand Teton / footprints 6031-6032 of 8354")
	)
	(layers
		(0 "F.Cu" signal "TOP")
		(4 "In1.Cu" signal "GND")
		(6 "In2.Cu" signal "IN1")
		(8 "In3.Cu" signal "GND1")
		(10 "In4.Cu" signal "IN2")
		(12 "In5.Cu" signal "GND2")
		(14 "In6.Cu" signal "IN3")
		(16 "In7.Cu" signal "GND3")
		(18 "In8.Cu" signal "VCC")
		(20 "In9.Cu" signal "VCC1")
		(22 "In10.Cu" signal "GND4")
		(24 "In11.Cu" signal "IN4")
		(26 "In12.Cu" signal "GND5")
		(28 "In13.Cu" signal "IN5")
		(30 "In14.Cu" signal "GND6")
		(32 "In15.Cu" signal "IN6")
		(34 "In16.Cu" signal "GND7")
		(2 "B.Cu" signal "BOTTOM")
		(9 "F.Adhes" user "F.Adhesive")
		(11 "B.Adhes" user "B.Adhesive")
		(13 "F.Paste" user "Package Geometry/Pastemask Top")
		(15 "B.Paste" user "Package Geometry/Pastemask Bottom")
		(5 "F.SilkS" user "Ref Des/Silkscreen Top")
		(7 "B.SilkS" user "Ref Des/Silkscreen Bottom")
		(1 "F.Mask" user "Board Geometry/Soldermask Top")
		(3 "B.Mask" user "Board Geometry/Soldermask Bottom")
		(17 "Dwgs.User" user "User.Drawings")
		(19 "Cmts.User" user "User.Comments")
		(21 "Eco1.User" user "User.Eco1")
		(23 "Eco2.User" user "User.Eco2")
		(25 "Edge.Cuts" user "Board Geometry/Outline")
		(27 "Margin" user)
		(31 "F.CrtYd" user "Package Geometry/Place Bound Top")
		(29 "B.CrtYd" user "Package Geometry/Place Bound Bottom")
		(35 "F.Fab" user "Ref Des/Assembly Top")
		(33 "B.Fab" user "Ref Des/Assembly Bottom")
	)
	(footprint ""
		(layer "B.Cu")
		(at 20.480782 -411.707584 180)
		(property "Reference" "PR6820"
			(at 0 0 0)
			(layer "B.SilkS")
			(hide yes)
			(effects
				(font
					(size 1.27 1.27)
				)
				(justify mirror)
			)
		)
		(property "Value" ""
			(at 0 0 0)
			(layer "B.Fab")
			(effects
				(font
					(size 1.27 1.27)
				)
				(justify mirror)
			)
		)
		(duplicate_pad_numbers_are_jumpers no)
		(fp_line
			(start 0.7874 0.4064)
			(end 0.7874 -0.4064)
			(stroke
				(width 0.1524)
				(type default)
			)
			(layer "B.SilkS")
		)
		(fp_line
			(start 0.7874 -0.4064)
			(end -0.7874 -0.4064)
			(stroke
				(width 0.1524)
				(type default)
			)
			(layer "B.SilkS")
		)
		(fp_line
			(start -0.7874 0.4064)
			(end 0.7874 0.4064)
			(stroke
				(width 0.1524)
				(type default)
			)
			(layer "B.SilkS")
		)
		(fp_line
			(start -0.7874 -0.4064)
			(end -0.7874 0.4064)
			(stroke
				(width 0.1524)
				(type default)
			)
			(layer "B.SilkS")
		)
		(fp_line
			(start 0.67945 0.3048)
			(end 0.67945 -0.305054)
			(stroke
				(width 0.1)
				(type default)
			)
			(layer "B.Fab")
		)
		(fp_line
			(start 0.67945 -0.305054)
			(end 0.12065 -0.305054)
			(stroke
				(width 0.1)
				(type default)
			)
			(layer "B.Fab")
		)
		(fp_line
			(start 0.12065 0.3048)
			(end 0.67945 0.3048)
			(stroke
				(width 0.1)
				(type default)
			)
			(layer "B.Fab")
		)
		(fp_line
			(start 0.12065 0.2794)
			(end 0.12065 0.3048)
			(stroke
				(width 0.1)
				(type default)
			)
			(layer "B.Fab")
		)
		(fp_line
			(start 0.12065 -0.2794)
			(end -0.12065 -0.2794)
			(stroke
				(width 0.1)
				(type default)
			)
			(layer "B.Fab")
		)
		(fp_line
			(start 0.12065 -0.305054)
			(end 0.12065 -0.2794)
			(stroke
				(width 0.1)
				(type default)
			)
			(layer "B.Fab")
		)
		(fp_line
			(start -0.120396 0.3048)
			(end -0.120396 0.2794)
			(stroke
				(width 0.1)
				(type default)
			)
			(layer "B.Fab")
		)
		(fp_line
			(start -0.120396 0.2794)
			(end 0.12065 0.2794)
			(stroke
				(width 0.1)
				(type default)
			)
			(layer "B.Fab")
		)
		(fp_line
			(start -0.12065 -0.2794)
			(end -0.12065 -0.3048)
			(stroke
				(width 0.1)
				(type default)
			)
			(layer "B.Fab")
		)
		(fp_line
			(start -0.12065 -0.3048)
			(end -0.67945 -0.3048)
			(stroke
				(width 0.1)
				(type default)
			)
			(layer "B.Fab")
		)
		(fp_line
			(start -0.67945 0.3048)
			(end -0.120396 0.3048)
			(stroke
				(width 0.1)
				(type default)
			)
			(layer "B.Fab")
		)
		(fp_line
			(start -0.67945 -0.3048)
			(end -0.67945 0.3048)
			(stroke
				(width 0.1)
				(type default)
			)
			(layer "B.Fab")
		)
		(pad "1" smd circle
			(at 0.40005 0)
			(size 0 0)
			(layers "B.Cu" "B.Mask" "B.Paste")
			(net "P0V9_RETIMER_CPU1_SVID_SDA")
		)
		(pad "2" smd circle
			(at -0.40005 0)
			(size 0 0)
			(layers "B.Cu" "B.Mask" "B.Paste")
			(net "GND")
		)
	)
	(footprint ""
		(layer "B.Cu")
		(at 99.273106 -390.560052 90)
		(property "Reference" "C351"
			(at 0 0 90)
			(layer "B.SilkS")
			(hide yes)
			(effects
				(font
					(size 1.27 1.27)
				)
				(justify mirror)
			)
		)
		(property "Value" ""
			(at 0 0 90)
			(layer "B.Fab")
			(effects
				(font
					(size 1.27 1.27)
				)
				(justify mirror)
			)
		)
		(duplicate_pad_numbers_are_jumpers no)
		(fp_line
			(start 0.7874 -0.4064)
			(end -0.7874 -0.4064)
			(stroke
				(width 0.1524)
				(type default)
			)
			(layer "B.SilkS")
		)
		(fp_line
			(start -0.7874 -0.4064)
			(end -0.7874 0.4064)
			(stroke
				(width 0.1524)
				(type default)
			)
			(layer "B.SilkS")
		)
		(fp_line
			(start 0.7874 0.4064)
			(end 0.7874 -0.4064)
			(stroke
				(width 0.1524)
				(type default)
			)
			(layer "B.SilkS")
		)
		(fp_line
			(start -0.7874 0.4064)
			(end 0.7874 0.4064)
			(stroke
				(width 0.1524)
				(type default)
			)
			(layer "B.SilkS")
		)
		(fp_line
			(start 0.67945 -0.305054)
			(end 0.12065 -0.305054)
			(stroke
				(width 0.1)
				(type default)
			)
			(layer "B.Fab")
		)
		(fp_line
			(start 0.12065 -0.305054)
			(end 0.12065 -0.2794)
			(stroke
				(width 0.1)
				(type default)
			)
			(layer "B.Fab")
		)
		(fp_line
			(start -0.12065 -0.3048)
			(end -0.67945 -0.3048)
			(stroke
				(width 0.1)
				(type default)
			)
			(layer "B.Fab")
		)
		(fp_line
			(start -0.67945 -0.3048)
			(end -0.67945 0.3048)
			(stroke
				(width 0.1)
				(type default)
			)
			(layer "B.Fab")
		)
		(fp_line
			(start 0.12065 -0.2794)
			(end -0.12065 -0.2794)
			(stroke
				(width 0.1)
				(type default)
			)
			(layer "B.Fab")
		)
		(fp_line
			(start -0.12065 -0.2794)
			(end -0.12065 -0.3048)
			(stroke
				(width 0.1)
				(type default)
			)
			(layer "B.Fab")
		)
		(fp_line
			(start 0.12065 0.2794)
			(end 0.12065 0.3048)
			(stroke
				(width 0.1)
				(type default)
			)
			(layer "B.Fab")
		)
		(fp_line
			(start -0.120396 0.2794)
			(end 0.12065 0.2794)
			(stroke
				(width 0.1)
				(type default)
			)
			(layer "B.Fab")
		)
		(fp_line
			(start 0.67945 0.3048)
			(end 0.67945 -0.305054)
			(stroke
				(width 0.1)
				(type default)
			)
			(layer "B.Fab")
		)
		(fp_line
			(start 0.12065 0.3048)
			(end 0.67945 0.3048)
			(stroke
				(width 0.1)
				(type default)
			)
			(layer "B.Fab")
		)
		(fp_line
			(start -0.120396 0.3048)
			(end -0.120396 0.2794)
			(stroke
				(width 0.1)
				(type default)
			)
			(layer "B.Fab")
		)
		(fp_line
			(start -0.67945 0.3048)
			(end -0.120396 0.3048)
			(stroke
				(width 0.1)
				(type default)
			)
			(layer "B.Fab")
		)
		(pad "1" smd circle
			(at 0.40005 0 270)
			(size 0 0)
			(layers "B.Cu" "B.Mask" "B.Paste")
			(net "P0V9_CPU1_RT1_2A")
		)
		(pad "2" smd circle
			(at -0.40005 0 270)
			(size 0 0)
			(layers "B.Cu" "B.Mask" "B.Paste")
			(net "GND")
		)
	)
)
